# BASEBOARD_FAB2 (Tioga Pass) — schematic netlist excerpt (pin names and nets, part order shuffled) for the footprints in the layout excerpt that follows; sources: Cadence DE-HDL packaged netlist, KiCad conversion of Wiwynn_Tioga_Pass_MB.brd

R6F4  RES  49.9 1% CHIP  pkg 0402  page 89 : A = IRQ_DIMM_SAVE_N ; B = FM_ADR_COMPLETE_ABC_N
R25W128  RES  150.0 1% CHIP  pkg 0402  page 252 : A = V_IO_R_J ; B = GND
R9F13  RES  10.0K 1% CHIP  pkg 0402  page 238 : A = P3V3_STBY ; B = PWRGD_P1V15_BMC_STBY_R

(kicad_pcb
	(version 20260206)
	(generator "pcbnew")
	(generator_version "10.0")
	(general
		(thickness 1.6)
		(legacy_teardrops no)
	)
	(paper "A4")
	(title_block
		(title "Wiwynn_Tioga_Pass_MB.brd")
		(comment 1 "Tioga Pass / footprints 2100-2102 of 4770")
	)
	(layers
		(0 "F.Cu" signal "TOP")
		(4 "In1.Cu" signal "L2GND")
		(6 "In2.Cu" signal "L3")
		(8 "In3.Cu" signal "L4GND")
		(10 "In4.Cu" signal "L5")
		(12 "In5.Cu" signal "L6GND")
		(14 "In6.Cu" signal "L7VCC")
		(16 "In7.Cu" signal "L8VCC")
		(18 "In8.Cu" signal "L9GND")
		(20 "In9.Cu" signal "L10")
		(22 "In10.Cu" signal "L11GND")
		(24 "In11.Cu" signal "L12")
		(26 "In12.Cu" signal "L13GND")
		(2 "B.Cu" signal "BOTTOM")
		(9 "F.Adhes" user "F.Adhesive")
		(11 "B.Adhes" user "B.Adhesive")
		(13 "F.Paste" user "Package Geometry/Pastemask Top")
		(15 "B.Paste" user "Package Geometry/Pastemask Bottom")
		(5 "F.SilkS" user "Ref Des/Silkscreen Top")
		(7 "B.SilkS" user "Ref Des/Silkscreen Bottom")
		(1 "F.Mask" user "Board Geometry/Soldermask Top")
		(3 "B.Mask" user "Board Geometry/Soldermask Bottom")
		(17 "Dwgs.User" user "User.Drawings")
		(19 "Cmts.User" user "User.Comments")
		(21 "Eco1.User" user "User.Eco1")
		(23 "Eco2.User" user "User.Eco2")
		(25 "Edge.Cuts" user "Board Geometry/Outline")
		(27 "Margin" user)
		(31 "F.CrtYd" user "Package Geometry/Place Bound Top")
		(29 "B.CrtYd" user "Package Geometry/Place Bound Bottom")
		(35 "F.Fab" user "Ref Des/Assembly Top")
		(33 "B.Fab" user "Ref Des/Assembly Bottom")
	)
	(footprint ""
		(layer "F.Cu")
		(at 323.723 -34.163 90)
		(property "Reference" "R6F4"
			(at 0 0 90)
			(layer "F.SilkS")
			(hide yes)
			(effects
				(font
					(size 1.27 1.27)
				)
			)
		)
		(property "Value" ""
			(at 0 0 90)
			(layer "F.Fab")
			(effects
				(font
					(size 1.27 1.27)
				)
			)
		)
		(duplicate_pad_numbers_are_jumpers no)
		(fp_poly
			(pts
				(xy -0.2794 -0.1016) (xy 0.2794 -0.1016) (xy 0.2794 0.9906) (xy -0.2794 0.9906)
			)
			(stroke
				(width 0)
				(type default)
			)
			(fill no)
			(layer "F.CrtYd")
		)
		(fp_line
			(start 0.2794 -0.1016)
			(end -0.2794 -0.1016)
			(stroke
				(width 0.1)
				(type default)
			)
			(layer "F.Fab")
		)
		(fp_line
			(start -0.2794 -0.1016)
			(end -0.2794 0.9906)
			(stroke
				(width 0.1)
				(type default)
			)
			(layer "F.Fab")
		)
		(fp_line
			(start 0.2794 0.9906)
			(end 0.2794 -0.1016)
			(stroke
				(width 0.1)
				(type default)
			)
			(layer "F.Fab")
		)
		(fp_line
			(start -0.2794 0.9906)
			(end 0.2794 0.9906)
			(stroke
				(width 0.1)
				(type default)
			)
			(layer "F.Fab")
		)
		(pad "1" smd rect
			(at 0 0 90)
			(size 0.508 0.508)
			(layers "F.Cu" "F.Mask" "F.Paste")
			(net "IRQ_DIMM_SAVE_N")
		)
		(pad "2" smd rect
			(at 0 0.889 90)
			(size 0.508 0.508)
			(layers "F.Cu" "F.Mask" "F.Paste")
			(net "FM_ADR_COMPLETE_ABC_N")
		)
		(zone
			(layer "F.Cu")
			(hatch none 0.5)
			(connect_pads
				(clearance 0)
			)
			(min_thickness 0.25)
			(keepout
				(tracks allowed)
				(vias not_allowed)
				(pads allowed)
				(copperpour not_allowed)
				(footprints allowed)
			)
			(placement
				(enabled no)
				(sheetname "")
			)
			(fill
				(thermal_gap 0.5)
				(thermal_bridge_width 0.5)
				(island_removal_mode 0)
			)
			(polygon
				(pts
					(xy 323.977 -33.909) (xy 323.977 -34.417) (xy 324.358 -34.417) (xy 324.358 -33.909)
				)
			)
		)
		(zone
			(layer "F.Cu")
			(hatch none 0.5)
			(connect_pads
				(clearance 0)
			)
			(min_thickness 0.25)
			(keepout
				(tracks not_allowed)
				(vias allowed)
				(pads allowed)
				(copperpour not_allowed)
				(footprints allowed)
			)
			(placement
				(enabled no)
				(sheetname "")
			)
			(fill
				(thermal_gap 0.5)
				(thermal_bridge_width 0.5)
				(island_removal_mode 0)
			)
			(polygon
				(pts
					(xy 324.358 -33.909) (xy 324.358 -34.417) (xy 323.977 -34.417) (xy 323.977 -33.909)
				)
			)
		)
	)
	(footprint ""
		(layer "F.Cu")
		(at 461.098392 -37.067998 180)
		(property "Reference" "R9F13"
			(at 0 0 180)
			(layer "F.SilkS")
			(hide yes)
			(effects
				(font
					(size 1.27 1.27)
				)
			)
		)
		(property "Value" ""
			(at 0 0 180)
			(layer "F.Fab")
			(effects
				(font
					(size 1.27 1.27)
				)
			)
		)
		(duplicate_pad_numbers_are_jumpers no)
		(fp_poly
			(pts
				(xy -0.2794 -0.1016) (xy 0.2794 -0.1016) (xy 0.2794 0.9906) (xy -0.2794 0.9906)
			)
			(stroke
				(width 0)
				(type default)
			)
			(fill no)
			(layer "F.CrtYd")
		)
		(fp_line
			(start 0.2794 0.9906)
			(end 0.2794 -0.1016)
			(stroke
				(width 0.1)
				(type default)
			)
			(layer "F.Fab")
		)
		(fp_line
			(start 0.2794 -0.1016)
			(end -0.2794 -0.1016)
			(stroke
				(width 0.1)
				(type default)
			)
			(layer "F.Fab")
		)
		(fp_line
			(start -0.2794 0.9906)
			(end 0.2794 0.9906)
			(stroke
				(width 0.1)
				(type default)
			)
			(layer "F.Fab")
		)
		(fp_line
			(start -0.2794 -0.1016)
			(end -0.2794 0.9906)
			(stroke
				(width 0.1)
				(type default)
			)
			(layer "F.Fab")
		)
		(pad "1" smd rect
			(at 0 0 180)
			(size 0.508 0.508)
			(layers "F.Cu" "F.Mask" "F.Paste")
			(net "P3V3_STBY")
		)
		(pad "2" smd rect
			(at 0 0.889 180)
			(size 0.508 0.508)
			(layers "F.Cu" "F.Mask" "F.Paste")
			(net "PWRGD_P1V15_BMC_STBY_R")
		)
		(zone
			(layer "F.Cu")
			(hatch none 0.5)
			(connect_pads
				(clearance 0)
			)
			(min_thickness 0.25)
			(keepout
				(tracks not_allowed)
				(vias allowed)
				(pads allowed)
				(copperpour not_allowed)
				(footprints allowed)
			)
			(placement
				(enabled no)
				(sheetname "")
			)
			(fill
				(thermal_gap 0.5)
				(thermal_bridge_width 0.5)
				(island_removal_mode 0)
			)
			(polygon
				(pts
					(xy 461.352392 -37.702998) (xy 460.844392 -37.702998) (xy 460.844392 -37.321998) (xy 461.352392 -37.321998)
				)
			)
		)
		(zone
			(layer "F.Cu")
			(hatch none 0.5)
			(connect_pads
				(clearance 0)
			)
			(min_thickness 0.25)
			(keepout
				(tracks allowed)
				(vias not_allowed)
				(pads allowed)
				(copperpour not_allowed)
				(footprints allowed)
			)
			(placement
				(enabled no)
				(sheetname "")
			)
			(fill
				(thermal_gap 0.5)
				(thermal_bridge_width 0.5)
				(island_removal_mode 0)
			)
			(polygon
				(pts
					(xy 461.352392 -37.321998) (xy 460.844392 -37.321998) (xy 460.844392 -37.702998) (xy 461.352392 -37.702998)
				)
			)
		)
	)
	(footprint ""
		(layer "F.Cu")
		(at 489.077 -33.655 -90)
		(property "Reference" "R25W128"
			(at -0.8382 -0.67818 270)
			(unlocked yes)
			(layer "F.SilkS")
			(effects
				(font
					(size 0.4064 0.254)
					(thickness 0.1524)
				)
				(justify left)
			)
		)
		(property "Value" ""
			(at 0 0 270)
			(layer "F.Fab")
			(effects
				(font
					(size 1.27 1.27)
				)
			)
		)
		(duplicate_pad_numbers_are_jumpers no)
		(fp_poly
			(pts
				(xy -0.2794 -0.1016) (xy 0.2794 -0.1016) (xy 0.2794 0.9906) (xy -0.2794 0.9906)
			)
			(stroke
				(width 0)
				(type default)
			)
			(fill no)
			(layer "F.CrtYd")
		)
		(fp_line
			(start -0.2794 0.9906)
			(end 0.2794 0.9906)
			(stroke
				(width 0.1)
				(type default)
			)
			(layer "F.Fab")
		)
		(fp_line
			(start 0.2794 0.9906)
			(end 0.2794 -0.1016)
			(stroke
				(width 0.1)
				(type default)
			)
			(layer "F.Fab")
		)
		(fp_line
			(start -0.2794 -0.1016)
			(end -0.2794 0.9906)
			(stroke
				(width 0.1)
				(type default)
			)
			(layer "F.Fab")
		)
		(fp_line
			(start 0.2794 -0.1016)
			(end -0.2794 -0.1016)
			(stroke
				(width 0.1)
				(type default)
			)
			(layer "F.Fab")
		)
		(pad "1" smd rect
			(at 0 0 270)
			(size 0.508 0.508)
			(layers "F.Cu" "F.Mask" "F.Paste")
			(net "V_IO_R_J")
		)
		(pad "2" smd rect
			(at 0 0.889 270)
			(size 0.508 0.508)
			(layers "F.Cu" "F.Mask" "F.Paste")
			(net "GND")
		)
		(zone
			(layer "F.Cu")
			(hatch none 0.5)
			(connect_pads
				(clearance 0)
			)
			(min_thickness 0.25)
			(keepout
				(tracks not_allowed)
				(vias allowed)
				(pads allowed)
				(copperpour not_allowed)
				(footprints allowed)
			)
			(placement
				(enabled no)
				(sheetname "")
			)
			(fill
				(thermal_gap 0.5)
				(thermal_bridge_width 0.5)
				(island_removal_mode 0)
			)
			(polygon
				(pts
					(xy 488.442 -33.909) (xy 488.442 -33.401) (xy 488.823 -33.401) (xy 488.823 -33.909)
				)
			)
		)
		(zone
			(layer "F.Cu")
			(hatch none 0.5)
			(connect_pads
				(clearance 0)
			)
			(min_thickness 0.25)
			(keepout
				(tracks allowed)
				(vias not_allowed)
				(pads allowed)
				(copperpour not_allowed)
				(footprints allowed)
			)
			(placement
				(enabled no)
				(sheetname "")
			)
			(fill
				(thermal_gap 0.5)
				(thermal_bridge_width 0.5)
				(island_removal_mode 0)
			)
			(polygon
				(pts
					(xy 488.823 -33.909) (xy 488.823 -33.401) (xy 488.442 -33.401) (xy 488.442 -33.909)
				)
			)
		)
	)
)
